# TIMECARD (Time Appliance Project (Time Card)) — schematic netlist excerpt (pin names and nets, part order shuffled) for the footprints in the layout excerpt that follows; sources: Cadence DE-HDL packaged netlist, KiCad conversion of R4006-B0001-02_R01.brd

C15  CAPACITOR  22UF 10V 20%  pkg SMC_0805R_H057  page 32 : \1\ = XP5R0V ; \2\ = SG
SP56  NULL  pkg DUMMY  page 34
SP60  NULL  pkg DUMMY  page 34
C267  CAPACITOR  100PF 10%  pkg SMC_0201R  page 29 : \1\ = UNNAMED_523_CAPACITOR_I28_1 ; \2\ = XP1R0V_FB_R_TO_AGND

(kicad_pcb
	(version 20260206)
	(generator "pcbnew")
	(generator_version "10.0")
	(general
		(thickness 1.6)
		(legacy_teardrops no)
	)
	(paper "A4")
	(title_block
		(title "timecard-production-celestica-r4006 — R4006-B0001-02_R01.brd")
		(comment 1 "Time Appliance Project (Time Card) / footprints 551-554 of 1113")
	)
	(layers
		(0 "F.Cu" signal "TOP")
		(4 "In1.Cu" signal "L02_GND1")
		(6 "In2.Cu" signal "L03_SIG1")
		(8 "In3.Cu" signal "L04_GND2")
		(10 "In4.Cu" signal "L05_VCC1")
		(12 "In5.Cu" signal "L06_VCC2")
		(14 "In6.Cu" signal "L07_GND3")
		(16 "In7.Cu" signal "L08_SIG2")
		(18 "In8.Cu" signal "L09_GND4")
		(2 "B.Cu" signal "BOTTOM")
		(9 "F.Adhes" user "F.Adhesive")
		(11 "B.Adhes" user "B.Adhesive")
		(13 "F.Paste" user "Package Geometry/Pastemask Top")
		(15 "B.Paste" user "Package Geometry/Pastemask Bottom")
		(5 "F.SilkS" user "Ref Des/Silkscreen Top")
		(7 "B.SilkS" user "Ref Des/Silkscreen Bottom")
		(1 "F.Mask" user "Board Geometry/Soldermask Top")
		(3 "B.Mask" user "Board Geometry/Soldermask Bottom")
		(17 "Dwgs.User" user "User.Drawings")
		(19 "Cmts.User" user "User.Comments")
		(21 "Eco1.User" user "User.Eco1")
		(23 "Eco2.User" user "User.Eco2")
		(25 "Edge.Cuts" user "Board Geometry/Outline")
		(27 "Margin" user)
		(31 "F.CrtYd" user "Package Geometry/Place Bound Top")
		(29 "B.CrtYd" user "Package Geometry/Place Bound Bottom")
		(35 "F.Fab" user "Ref Des/Assembly Top")
		(33 "B.Fab" user "Ref Des/Assembly Bottom")
	)
	(footprint ""
		(layer "F.Cu")
		(at 57.4294 -103.4034 90)
		(property "Reference" "C15"
			(at -0.0254 3.18897 90)
			(unlocked yes)
			(layer "F.SilkS")
			(effects
				(font
					(size 0.7874 0.5842)
					(thickness 0.1524)
				)
			)
		)
		(property "Value" "VAL*"
			(at 0.0762 3.134106 90)
			(unlocked yes)
			(layer "F.Fab")
			(hide yes)
			(effects
				(font
					(size 0.7874 0.5842)
					(thickness 0.1524)
				)
			)
		)
		(property "Device Type" "CAPACITOR-G107-0F226-CM,22UF,2A"
			(at 0.0508 2.194306 90)
			(unlocked yes)
			(layer "F.Fab")
			(hide yes)
			(effects
				(font
					(size 0.7874 0.5842)
					(thickness 0.1524)
				)
			)
		)
		(property "User Part Number" "PARTNUM*"
			(at 0.1016 5.013706 90)
			(unlocked yes)
			(layer "Cmts.User")
			(hide yes)
			(effects
				(font
					(size 0.7874 0.5842)
					(thickness 0.1524)
				)
			)
		)
		(property "Tolerance" "TOL*"
			(at 0.0762 4.048506 90)
			(unlocked yes)
			(layer "Cmts.User")
			(hide yes)
			(effects
				(font
					(size 0.7874 0.5842)
					(thickness 0.1524)
				)
			)
		)
		(duplicate_pad_numbers_are_jumpers no)
		(fp_line
			(start 1.5748 -0.9398)
			(end -1.5748 -0.9398)
			(stroke
				(width 0.1)
				(type default)
			)
			(layer "F.SilkS")
		)
		(fp_line
			(start -1.5748 -0.9398)
			(end -1.5748 0.9398)
			(stroke
				(width 0.1)
				(type default)
			)
			(layer "F.SilkS")
		)
		(fp_line
			(start 1.5748 0.9398)
			(end 1.5748 -0.9398)
			(stroke
				(width 0.1)
				(type default)
			)
			(layer "F.SilkS")
		)
		(fp_line
			(start -1.5748 0.9398)
			(end 1.5748 0.9398)
			(stroke
				(width 0.1)
				(type default)
			)
			(layer "F.SilkS")
		)
		(fp_rect
			(start 1.5748 0.9398)
			(end -1.5748 -0.9398)
			(stroke
				(width 0)
				(type default)
			)
			(fill no)
			(layer "F.CrtYd")
		)
		(fp_line
			(start 1.016 -0.635)
			(end -1.016 -0.635)
			(stroke
				(width 0.1)
				(type default)
			)
			(layer "F.Fab")
		)
		(fp_line
			(start -1.016 -0.635)
			(end -1.016 0.635)
			(stroke
				(width 0.1)
				(type default)
			)
			(layer "F.Fab")
		)
		(fp_line
			(start 1.016 0.635)
			(end 1.016 -0.635)
			(stroke
				(width 0.1)
				(type default)
			)
			(layer "F.Fab")
		)
		(fp_line
			(start -1.016 0.635)
			(end 1.016 0.635)
			(stroke
				(width 0.1)
				(type default)
			)
			(layer "F.Fab")
		)
		(pad "1" smd rect
			(at -0.8382 0 90)
			(size 0.9652 1.3716)
			(layers "F.Cu" "F.Mask" "F.Paste")
			(net "XP5R0V")
		)
		(pad "2" smd rect
			(at 0.8382 0 90)
			(size 0.9652 1.3716)
			(layers "F.Cu" "F.Mask" "F.Paste")
			(net "SG")
		)
		(zone
			(layer "F.Cu")
			(hatch none 0.5)
			(connect_pads
				(clearance 0)
			)
			(min_thickness 0.25)
			(keepout
				(tracks allowed)
				(vias not_allowed)
				(pads allowed)
				(copperpour not_allowed)
				(footprints allowed)
			)
			(placement
				(enabled no)
				(sheetname "")
			)
			(fill
				(thermal_gap 0.5)
				(thermal_bridge_width 0.5)
				(island_removal_mode 0)
			)
			(polygon
				(pts
					(xy 58.0644 -103.632) (xy 56.7944 -103.632) (xy 56.7944 -103.1748) (xy 58.0644 -103.1748)
				)
			)
		)
	)
	(footprint ""
		(layer "F.Cu")
		(at 144.653 -59.563 -90)
		(property "Reference" "C267"
			(at -3.048 2.11963 90)
			(unlocked yes)
			(layer "F.SilkS")
			(effects
				(font
					(size 0.7874 0.5842)
					(thickness 0.1524)
				)
			)
		)
		(property "Value" "VAL*"
			(at 0.193548 2.13614 270)
			(unlocked yes)
			(layer "F.Fab")
			(hide yes)
			(effects
				(font
					(size 0.7874 0.5842)
					(thickness 0.1524)
				)
			)
		)
		(property "Tolerance" "TOL*"
			(at 0.216154 3.1496 270)
			(unlocked yes)
			(layer "Cmts.User")
			(hide yes)
			(effects
				(font
					(size 0.7874 0.5842)
					(thickness 0.1524)
				)
			)
		)
		(property "Device Type" "CAPACITOR-G104-0B101-FK,100PF,A"
			(at 0.184404 1.180592 270)
			(unlocked yes)
			(layer "F.Fab")
			(hide yes)
			(effects
				(font
					(size 0.7874 0.5842)
					(thickness 0.1524)
				)
			)
		)
		(property "User Part Number" "PARTNUM*"
			(at 0.216154 4.185666 270)
			(unlocked yes)
			(layer "Cmts.User")
			(hide yes)
			(effects
				(font
					(size 0.7874 0.5842)
					(thickness 0.1524)
				)
			)
		)
		(duplicate_pad_numbers_are_jumpers no)
		(fp_line
			(start -0.671322 0.4445)
			(end -0.671322 -0.4445)
			(stroke
				(width 0.1)
				(type default)
			)
			(layer "F.SilkS")
		)
		(fp_line
			(start 0.671322 0.4445)
			(end -0.671322 0.4445)
			(stroke
				(width 0.1)
				(type default)
			)
			(layer "F.SilkS")
		)
		(fp_line
			(start -0.671322 -0.4445)
			(end 0.671322 -0.4445)
			(stroke
				(width 0.1)
				(type default)
			)
			(layer "F.SilkS")
		)
		(fp_line
			(start 0.671322 -0.4445)
			(end 0.671322 0.4445)
			(stroke
				(width 0.1)
				(type default)
			)
			(layer "F.SilkS")
		)
		(fp_rect
			(start 0.671322 0.4445)
			(end -0.671322 -0.4445)
			(stroke
				(width 0)
				(type default)
			)
			(fill no)
			(layer "F.CrtYd")
		)
		(fp_line
			(start -0.31496 0.1651)
			(end 0.31496 0.1651)
			(stroke
				(width 0.1)
				(type default)
			)
			(layer "F.Fab")
		)
		(fp_line
			(start 0.31496 0.1651)
			(end 0.31496 -0.1651)
			(stroke
				(width 0.1)
				(type default)
			)
			(layer "F.Fab")
		)
		(fp_line
			(start -0.31496 -0.1651)
			(end -0.31496 0.1651)
			(stroke
				(width 0.1)
				(type default)
			)
			(layer "F.Fab")
		)
		(fp_line
			(start 0.31496 -0.1651)
			(end -0.31496 -0.1651)
			(stroke
				(width 0.1)
				(type default)
			)
			(layer "F.Fab")
		)
		(pad "1" smd rect
			(at -0.264922 0 270)
			(size 0.3048 0.381)
			(layers "F.Cu" "F.Mask" "F.Paste")
			(net "UNNAMED_523_CAPACITOR_I28_1")
		)
		(pad "2" smd rect
			(at 0.264922 0 270)
			(size 0.3048 0.381)
			(layers "F.Cu" "F.Mask" "F.Paste")
			(net "XP1R0V_FB_R_TO_AGND")
		)
		(zone
			(layer "F.Cu")
			(hatch none 0.5)
			(connect_pads
				(clearance 0)
			)
			(min_thickness 0.25)
			(keepout
				(tracks allowed)
				(vias not_allowed)
				(pads allowed)
				(copperpour not_allowed)
				(footprints allowed)
			)
			(placement
				(enabled no)
				(sheetname "")
			)
			(fill
				(thermal_gap 0.5)
				(thermal_bridge_width 0.5)
				(island_removal_mode 0)
			)
			(polygon
				(pts
					(xy 144.4625 -59.450478) (xy 144.8435 -59.450478) (xy 144.8435 -59.675522) (xy 144.4625 -59.675522)
				)
			)
		)
	)
	(footprint ""
		(layer "F.Cu")
		(at 54.737 -125.349)
		(property "Reference" "SP56"
			(at 0 0 0)
			(layer "F.SilkS")
			(hide yes)
			(effects
				(font
					(size 1.27 1.27)
				)
			)
		)
		(property "Value" ""
			(at 0 0 0)
			(layer "F.Fab")
			(effects
				(font
					(size 1.27 1.27)
				)
			)
		)
		(duplicate_pad_numbers_are_jumpers no)
	)
	(footprint ""
		(layer "F.Cu")
		(at 53.594 -131.699)
		(property "Reference" "SP60"
			(at 0 0 0)
			(layer "F.SilkS")
			(hide yes)
			(effects
				(font
					(size 1.27 1.27)
				)
			)
		)
		(property "Value" ""
			(at 0 0 0)
			(layer "F.Fab")
			(effects
				(font
					(size 1.27 1.27)
				)
			)
		)
		(duplicate_pad_numbers_are_jumpers no)
	)
)
